(kicad_pcb
	(version 20241229)
	(generator "pcbnew")
	(generator_version "9.0")
	(general
		(thickness 1.711)
		(legacy_teardrops no)
	)
	(paper "A4")
	(title_block
		(title "Antmicro Baseboard for Jetson AGX Thor")
		(date "2026-02-18")
		(rev "1.1.0")
		(company "Antmicro Ltd")
		(comment 1 "www.antmicro.com")
		(comment 9 "footprint 305 of 1170 (U5), pads 1-24 of 24")
	)
	(layers
		(0 "F.Cu" signal)
		(4 "In1.Cu" signal)
		(6 "In2.Cu" signal)
		(8 "In3.Cu" signal)
		(10 "In4.Cu" jumper)
		(12 "In5.Cu" signal)
		(14 "In6.Cu" signal)
		(16 "In7.Cu" signal)
		(18 "In8.Cu" signal)
		(2 "B.Cu" signal)
		(9 "F.Adhes" user "F.Adhesive")
		(11 "B.Adhes" user "B.Adhesive")
		(13 "F.Paste" user)
		(15 "B.Paste" user)
		(5 "F.SilkS" user "F.Silkscreen")
		(7 "B.SilkS" user "B.Silkscreen")
		(1 "F.Mask" user)
		(3 "B.Mask" user)
		(17 "Dwgs.User" user "User.Drawings")
		(19 "Cmts.User" user "User.Comments")
		(21 "Eco1.User" user "User.Eco1")
		(23 "Eco2.User" user "User.Eco2")
		(25 "Edge.Cuts" user)
		(27 "Margin" user)
		(31 "F.CrtYd" user "F.Courtyard")
		(29 "B.CrtYd" user "B.Courtyard")
		(35 "F.Fab" user)
		(33 "B.Fab" user)
	)
	(footprint "antmicro-footprints:UQFN-24_2x4mm_P0.4mm_Texas_RJW0024A"
		(layer "F.Cu")
		(at 152.5 99)
		(property "Reference" "U5"
			(at -2.9 -1.5 0)
			(unlocked yes)
			(layer "F.SilkS")
			(effects
				(font
					(size 0.7 0.7)
					(thickness 0.15)
				)
				(justify left bottom)
			)
		)
		(property "Value" "SN74AXC8T245_UQFN"
			(at 0 3.4 0)
			(unlocked yes)
			(layer "F.Fab")
			(effects
				(font
					(size 0.7 0.7)
					(thickness 0.15)
				)
				(justify left bottom)
			)
		)
		(property "Datasheet" "https://www.ti.com/lit/ds/symlink/sn74axc8t245.pdf?ts=1702327536011"
			(at 0 0 0)
			(layer "F.Fab")
			(hide yes)
			(effects
				(font
					(size 1.27 1.27)
					(thickness 0.15)
				)
			)
		)
		(property "Description" "8-bit dual-supply bus transceiver"
			(at 0 0 0)
			(layer "F.Fab")
			(hide yes)
			(effects
				(font
					(size 1.27 1.27)
					(thickness 0.15)
				)
			)
		)
		(property "MPN" "SN74AXC8T245RJWR"
			(at 0 0 0)
			(unlocked yes)
			(layer "F.Fab")
			(hide yes)
			(effects
				(font
					(size 1 1)
					(thickness 0.15)
				)
			)
		)
		(property "Manufacturer" "Texas Instruments"
			(at 0 0 0)
			(unlocked yes)
			(layer "F.Fab")
			(hide yes)
			(effects
				(font
					(size 1 1)
					(thickness 0.15)
				)
			)
		)
		(property "Author" "Antmicro"
			(at 0 0 0)
			(unlocked yes)
			(layer "F.Fab")
			(hide yes)
			(effects
				(font
					(size 1 1)
					(thickness 0.15)
				)
			)
		)
		(property "License" "Apache-2.0"
			(at 0 0 0)
			(unlocked yes)
			(layer "F.Fab")
			(hide yes)
			(effects
				(font
					(size 1 1)
					(thickness 0.15)
				)
			)
		)
		(sheetname "/SoM_IO/")
		(sheetfile "som_io.kicad_sch")
		(attr smd)
		(pad "1" smd rect
			(at -0.85 -1.8)
			(size 0.700001 0.2)
			(layers "F.Cu" "F.Mask")
			(net 11 "+1V8")
			(pinfunction "DIR1")
			(pintype "input")
		)
		(pad "2" smd rect
			(at -0.85 -1.4)
			(size 0.700001 0.2)
			(layers "F.Cu" "F.Mask")
			(net 1 "GND")
			(pinfunction "A1")
			(pintype "bidirectional")
		)
		(pad "3" smd rect
			(at -0.7 -1)
			(size 1 0.2)
			(layers "F.Cu" "F.Mask")
			(net 906 "/SoM_IO/M2_E_W_DIS_1_1V8")
			(pinfunction "A2")
			(pintype "bidirectional")
		)
		(pad "4" smd rect
			(at -0.7 -0.6)
			(size 1 0.2)
			(layers "F.Cu" "F.Mask")
			(net 878 "/SoM_IO/M2_E_W_DIS_2_1V8")
			(pinfunction "A3")
			(pintype "bidirectional")
		)
		(pad "5" smd rect
			(at -0.7 -0.2)
			(size 1 0.2)
			(layers "F.Cu" "F.Mask")
			(net 496 "/SoM_IO/UART3_DEBUG_TX_1V8")
			(pinfunction "A4")
			(pintype "bidirectional")
		)
		(pad "6" smd rect
			(at -0.7 0.2)
			(size 1 0.2)
			(layers "F.Cu" "F.Mask")
			(net 494 "/SoM_IO/UART3_DEBUG_RX_1V8")
			(pinfunction "A5")
			(pintype "bidirectional")
		)
		(pad "7" smd rect
			(at -0.7 0.6)
			(size 1 0.2)
			(layers "F.Cu" "F.Mask")
			(net 580 "/SoM_IO/USBC1_FLG_1V8")
			(pinfunction "A6")
			(pintype "bidirectional")
		)
		(pad "8" smd rect
			(at -0.7 1)
			(size 1 0.2)
			(layers "F.Cu" "F.Mask")
			(net 1292 "/SoM_IO/GPIO_EXP_IRQ_1V8")
			(pinfunction "A7")
			(pintype "bidirectional")
		)
		(pad "9" smd rect
			(at -0.85 1.4)
			(size 0.700001 0.2)
			(layers "F.Cu" "F.Mask")
			(net 1339 "unconnected-(U5-A8-Pad9)")
			(pinfunction "A8")
			(pintype "bidirectional+no_connect")
		)
		(pad "10" smd rect
			(at -0.85 1.8)
			(size 0.700001 0.2)
			(layers "F.Cu" "F.Mask")
			(net 11 "+1V8")
			(pinfunction "DIR2")
			(pintype "input")
		)
		(pad "11" smd rect
			(at -0.199999 1.825 90)
			(size 0.750001 0.2)
			(layers "F.Cu" "F.Mask")
			(net 1 "GND")
			(pinfunction "GND")
			(pintype "power_in")
		)
		(pad "12" smd rect
			(at 0.199999 1.825 90)
			(size 0.750001 0.2)
			(layers "F.Cu" "F.Mask")
			(net 1 "GND")
			(pinfunction "GND")
			(pintype "passive")
		)
		(pad "13" smd rect
			(at 0.85 1.8)
			(size 0.700001 0.2)
			(layers "F.Cu" "F.Mask")
			(net 1 "GND")
			(pinfunction "B8")
			(pintype "bidirectional")
		)
		(pad "14" smd rect
			(at 0.85 1.4)
			(size 0.700001 0.2)
			(layers "F.Cu" "F.Mask")
			(net 1309 "/Peripherals/GPIO_EXP_IRQ")
			(pinfunction "B7")
			(pintype "bidirectional")
		)
		(pad "15" smd rect
			(at 0.7 1)
			(size 1 0.2)
			(layers "F.Cu" "F.Mask")
			(net 962 "/SoM_IO/USBC1_FLG")
			(pinfunction "B6")
			(pintype "bidirectional")
		)
		(pad "16" smd rect
			(at 0.7 0.6)
			(size 1 0.2)
			(layers "F.Cu" "F.Mask")
			(net 960 "/SoM_IO/UART3_DEBUG.RX")
			(pinfunction "B5")
			(pintype "bidirectional")
		)
		(pad "17" smd rect
			(at 0.7 0.2)
			(size 1 0.2)
			(layers "F.Cu" "F.Mask")
			(net 959 "/SoM_IO/UART3_DEBUG.TX")
			(pinfunction "B4")
			(pintype "bidirectional")
		)
		(pad "18" smd rect
			(at 0.7 -0.2)
			(size 1 0.2)
			(layers "F.Cu" "F.Mask")
			(net 1167 "/M.2/M2_E.W_DIS_2")
			(pinfunction "B3")
			(pintype "bidirectional")
		)
		(pad "19" smd rect
			(at 0.7 -0.6)
			(size 1 0.2)
			(layers "F.Cu" "F.Mask")
			(net 1113 "/M.2/M2_E.W_DIS_1")
			(pinfunction "B2")
			(pintype "bidirectional")
		)
		(pad "20" smd rect
			(at 0.7 -1)
			(size 1 0.2)
			(layers "F.Cu" "F.Mask")
			(net 1338 "unconnected-(U5-B1-Pad20)")
			(pinfunction "B1")
			(pintype "bidirectional+no_connect")
		)
		(pad "21" smd rect
			(at 0.85 -1.4)
			(size 0.700001 0.2)
			(layers "F.Cu" "F.Mask")
			(net 1 "GND")
			(pinfunction "OE_N")
			(pintype "input")
		)
		(pad "22" smd rect
			(at 0.85 -1.8)
			(size 0.700001 0.2)
			(layers "F.Cu" "F.Mask")
			(net 2 "+3V3")
			(pinfunction "VCCB")
			(pintype "power_in")
		)
		(pad "23" smd rect
			(at 0.199999 -1.825 90)
			(size 0.750001 0.2)
			(layers "F.Cu" "F.Mask")
			(net 2 "+3V3")
			(pinfunction "VCCB")
			(pintype "passive")
		)
		(pad "24" smd rect
			(at -0.199999 -1.825 90)
			(size 0.750001 0.2)
			(layers "F.Cu" "F.Mask")
			(net 11 "+1V8")
			(pinfunction "VCCA")
			(pintype "power_in")
		)
	)
)
